#ISCELL
  mstr_misc dns *
  *
#ISCELL
  pure_quanta quanta_title_block_c *
  *
#ISCELL
  pure_quanta_power p1v0 *
  page452_i10
#ISCELL
  pure_quanta_power vcc_core *
  page452_i11
#ISCELL
  pure_quanta_power vcc_core *
  page452_i12
#ISCELL
  pure_quanta_power universal_gnd *
  page452_i13
#ISCELL
  pure_quanta_power universal_gnd *
  page452_i14
#CELL
  pure_quanta q_res *
  page452_i15
#ISCELL
  pure_quanta_power universal_gnd *
  page452_i16
#ISCELL
  pure_quanta_power universal_gnd *
  page452_i17
#CELL
  pure_quanta q_res *
  page452_i18
#CELL
  pure_quanta pt5161lrs *
  page452_i19
#CELL
  pure_quanta q_res *
  page452_i20
#CELL
  pure_quanta q_res *
  page452_i21
#ISCELL
  pure_quanta_power p1v0 *
  page452_i4
#ISCELL
  pure_quanta_power universal_gnd *
  page452_i5
#CELL
  pure_quanta pt5161lrs *
  page452_i7
#ISCELL
  pure_quanta_power p1v0 *
  page452_i8
#ISCELL
  pure_quanta_power p1v0 *
  page452_i9
